# T6G (Grand Teton) — schematic netlist excerpt (pin names and nets, part order shuffled) for the footprints in the layout excerpt that follows; sources: Cadence DE-HDL packaged netlist, KiCad conversion of 04192023_DAF0TMB3IC0_F0TG_MB_C_brd_V02_OCP.brd

R6326  Q_RES  4.7K 1% CHIP  pkg 0402LF  page 178 : A = USB_HUB2_MRP_PROG_FUNC6 ; B = GND
C2572  Q_CAP  22UF 4V 20% X6S  pkg C0402  page 70 : A = PVDDCR_SOC_P0 ; B = GND

(kicad_pcb
	(version 20260206)
	(generator "pcbnew")
	(generator_version "10.0")
	(general
		(thickness 1.6)
		(legacy_teardrops no)
	)
	(paper "A4")
	(title_block
		(title "04192023_DAF0TMB3IC0_F0TG_MB_C_brd_V02_OCP.brd")
		(comment 1 "Grand Teton / footprints 2877-2878 of 8354")
	)
	(layers
		(0 "F.Cu" signal "TOP")
		(4 "In1.Cu" signal "GND")
		(6 "In2.Cu" signal "IN1")
		(8 "In3.Cu" signal "GND1")
		(10 "In4.Cu" signal "IN2")
		(12 "In5.Cu" signal "GND2")
		(14 "In6.Cu" signal "IN3")
		(16 "In7.Cu" signal "GND3")
		(18 "In8.Cu" signal "VCC")
		(20 "In9.Cu" signal "VCC1")
		(22 "In10.Cu" signal "GND4")
		(24 "In11.Cu" signal "IN4")
		(26 "In12.Cu" signal "GND5")
		(28 "In13.Cu" signal "IN5")
		(30 "In14.Cu" signal "GND6")
		(32 "In15.Cu" signal "IN6")
		(34 "In16.Cu" signal "GND7")
		(2 "B.Cu" signal "BOTTOM")
		(9 "F.Adhes" user "F.Adhesive")
		(11 "B.Adhes" user "B.Adhesive")
		(13 "F.Paste" user "Package Geometry/Pastemask Top")
		(15 "B.Paste" user "Package Geometry/Pastemask Bottom")
		(5 "F.SilkS" user "Ref Des/Silkscreen Top")
		(7 "B.SilkS" user "Ref Des/Silkscreen Bottom")
		(1 "F.Mask" user "Board Geometry/Soldermask Top")
		(3 "B.Mask" user "Board Geometry/Soldermask Bottom")
		(17 "Dwgs.User" user "User.Drawings")
		(19 "Cmts.User" user "User.Comments")
		(21 "Eco1.User" user "User.Eco1")
		(23 "Eco2.User" user "User.Eco2")
		(25 "Edge.Cuts" user "Board Geometry/Outline")
		(27 "Margin" user)
		(31 "F.CrtYd" user "Package Geometry/Place Bound Top")
		(29 "B.CrtYd" user "Package Geometry/Place Bound Bottom")
		(35 "F.Fab" user "Ref Des/Assembly Top")
		(33 "B.Fab" user "Ref Des/Assembly Bottom")
	)
	(footprint ""
		(layer "F.Cu")
		(at 103.413814 -36.6522 180)
		(property "Reference" "R6326"
			(at 0 0 180)
			(layer "F.SilkS")
			(hide yes)
			(effects
				(font
					(size 1.27 1.27)
				)
			)
		)
		(property "Value" ""
			(at 0 0 180)
			(layer "F.Fab")
			(effects
				(font
					(size 1.27 1.27)
				)
			)
		)
		(duplicate_pad_numbers_are_jumpers no)
		(fp_line
			(start 0.7874 0.4064)
			(end -0.7874 0.4064)
			(stroke
				(width 0.1524)
				(type default)
			)
			(layer "F.SilkS")
		)
		(fp_line
			(start 0.7874 -0.4064)
			(end 0.7874 0.4064)
			(stroke
				(width 0.1524)
				(type default)
			)
			(layer "F.SilkS")
		)
		(fp_line
			(start -0.7874 0.4064)
			(end -0.7874 -0.4064)
			(stroke
				(width 0.1524)
				(type default)
			)
			(layer "F.SilkS")
		)
		(fp_line
			(start -0.7874 -0.4064)
			(end 0.7874 -0.4064)
			(stroke
				(width 0.1524)
				(type default)
			)
			(layer "F.SilkS")
		)
		(fp_line
			(start 0.67945 0.3048)
			(end 0.120396 0.3048)
			(stroke
				(width 0.1)
				(type default)
			)
			(layer "F.Fab")
		)
		(fp_line
			(start 0.67945 -0.3048)
			(end 0.67945 0.3048)
			(stroke
				(width 0.1)
				(type default)
			)
			(layer "F.Fab")
		)
		(fp_line
			(start 0.12065 -0.2794)
			(end 0.12065 -0.3048)
			(stroke
				(width 0.1)
				(type default)
			)
			(layer "F.Fab")
		)
		(fp_line
			(start 0.12065 -0.3048)
			(end 0.67945 -0.3048)
			(stroke
				(width 0.1)
				(type default)
			)
			(layer "F.Fab")
		)
		(fp_line
			(start 0.120396 0.3048)
			(end 0.120396 0.2794)
			(stroke
				(width 0.1)
				(type default)
			)
			(layer "F.Fab")
		)
		(fp_line
			(start 0.120396 0.2794)
			(end -0.12065 0.2794)
			(stroke
				(width 0.1)
				(type default)
			)
			(layer "F.Fab")
		)
		(fp_line
			(start -0.12065 0.3048)
			(end -0.67945 0.3048)
			(stroke
				(width 0.1)
				(type default)
			)
			(layer "F.Fab")
		)
		(fp_line
			(start -0.12065 0.2794)
			(end -0.12065 0.3048)
			(stroke
				(width 0.1)
				(type default)
			)
			(layer "F.Fab")
		)
		(fp_line
			(start -0.12065 -0.2794)
			(end 0.12065 -0.2794)
			(stroke
				(width 0.1)
				(type default)
			)
			(layer "F.Fab")
		)
		(fp_line
			(start -0.12065 -0.305054)
			(end -0.12065 -0.2794)
			(stroke
				(width 0.1)
				(type default)
			)
			(layer "F.Fab")
		)
		(fp_line
			(start -0.67945 0.3048)
			(end -0.67945 -0.305054)
			(stroke
				(width 0.1)
				(type default)
			)
			(layer "F.Fab")
		)
		(fp_line
			(start -0.67945 -0.305054)
			(end -0.12065 -0.305054)
			(stroke
				(width 0.1)
				(type default)
			)
			(layer "F.Fab")
		)
		(pad "1" smd circle
			(at -0.40005 0 180)
			(size 0 0)
			(layers "F.Cu" "F.Mask" "F.Paste")
			(net "USB_HUB2_MRP_PROG_FUNC6")
		)
		(pad "2" smd circle
			(at 0.40005 0 180)
			(size 0 0)
			(layers "F.Cu" "F.Mask" "F.Paste")
			(net "GND")
		)
	)
	(footprint ""
		(layer "F.Cu")
		(at 358.797098 -257.744976)
		(property "Reference" "C2572"
			(at 0 0 0)
			(layer "F.SilkS")
			(hide yes)
			(effects
				(font
					(size 1.27 1.27)
				)
			)
		)
		(property "Value" ""
			(at 0 0 0)
			(layer "F.Fab")
			(effects
				(font
					(size 1.27 1.27)
				)
			)
		)
		(duplicate_pad_numbers_are_jumpers no)
		(fp_line
			(start -0.7874 -0.4064)
			(end 0.7874 -0.4064)
			(stroke
				(width 0.1524)
				(type default)
			)
			(layer "F.SilkS")
		)
		(fp_line
			(start -0.7874 0.4064)
			(end -0.7874 -0.4064)
			(stroke
				(width 0.1524)
				(type default)
			)
			(layer "F.SilkS")
		)
		(fp_line
			(start 0.7874 -0.4064)
			(end 0.7874 0.4064)
			(stroke
				(width 0.1524)
				(type default)
			)
			(layer "F.SilkS")
		)
		(fp_line
			(start 0.7874 0.4064)
			(end -0.7874 0.4064)
			(stroke
				(width 0.1524)
				(type default)
			)
			(layer "F.SilkS")
		)
		(fp_line
			(start -0.67945 -0.305054)
			(end -0.12065 -0.305054)
			(stroke
				(width 0.1)
				(type default)
			)
			(layer "F.Fab")
		)
		(fp_line
			(start -0.67945 0.3048)
			(end -0.67945 -0.305054)
			(stroke
				(width 0.1)
				(type default)
			)
			(layer "F.Fab")
		)
		(fp_line
			(start -0.12065 -0.305054)
			(end -0.12065 -0.2794)
			(stroke
				(width 0.1)
				(type default)
			)
			(layer "F.Fab")
		)
		(fp_line
			(start -0.12065 -0.2794)
			(end 0.12065 -0.2794)
			(stroke
				(width 0.1)
				(type default)
			)
			(layer "F.Fab")
		)
		(fp_line
			(start -0.12065 0.2794)
			(end -0.12065 0.3048)
			(stroke
				(width 0.1)
				(type default)
			)
			(layer "F.Fab")
		)
		(fp_line
			(start -0.12065 0.3048)
			(end -0.67945 0.3048)
			(stroke
				(width 0.1)
				(type default)
			)
			(layer "F.Fab")
		)
		(fp_line
			(start 0.120396 0.2794)
			(end -0.12065 0.2794)
			(stroke
				(width 0.1)
				(type default)
			)
			(layer "F.Fab")
		)
		(fp_line
			(start 0.120396 0.3048)
			(end 0.120396 0.2794)
			(stroke
				(width 0.1)
				(type default)
			)
			(layer "F.Fab")
		)
		(fp_line
			(start 0.12065 -0.3048)
			(end 0.67945 -0.3048)
			(stroke
				(width 0.1)
				(type default)
			)
			(layer "F.Fab")
		)
		(fp_line
			(start 0.12065 -0.2794)
			(end 0.12065 -0.3048)
			(stroke
				(width 0.1)
				(type default)
			)
			(layer "F.Fab")
		)
		(fp_line
			(start 0.67945 -0.3048)
			(end 0.67945 0.3048)
			(stroke
				(width 0.1)
				(type default)
			)
			(layer "F.Fab")
		)
		(fp_line
			(start 0.67945 0.3048)
			(end 0.120396 0.3048)
			(stroke
				(width 0.1)
				(type default)
			)
			(layer "F.Fab")
		)
		(pad "1" smd circle
			(at -0.40005 0)
			(size 0 0)
			(layers "F.Cu" "F.Mask" "F.Paste")
			(net "PVDDCR_SOC_P0")
		)
		(pad "2" smd circle
			(at 0.40005 0)
			(size 0 0)
			(layers "F.Cu" "F.Mask" "F.Paste")
			(net "GND")
		)
	)
)
